# BASEBOARD_FAB2 (Tioga Pass) — schematic netlist excerpt (pin names and nets, part order shuffled) for the footprints in the layout excerpt that follows; sources: Cadence DE-HDL packaged netlist, KiCad conversion of Wiwynn_Tioga_Pass_MB.brd

J9T1  SCONN288_H44441003  SCONN  pkg PIP  page 78
  \12v\(1)  = P12V_NVDIMM_GHJ
  VSS(93)  = GND
  DQ(4)  = M_G_DQ<4>
  VSS(92)  = GND
  DQ(0)  = M_G_DQ<0>
  VSS(91)  = GND
  DQS9P  = M_G_DQS_DP<9>
  DQS9N  = M_G_DQS_DN<9>
  VSS(90)  = GND
  DQ(6)  = M_G_DQ<6>
  VSS(89)  = GND
  DQ(2)  = M_G_DQ<2>
  VSS(88)  = GND
  DQ(12)  = M_G_DQ<12>
  VSS(87)  = GND
  DQ(8)  = M_G_DQ<8>
  VSS(86)  = GND
  DQS10P  = M_G_DQS_DP<10>
  DQS10N  = M_G_DQS_DN<10>
  VSS(85)  = GND
  DQ(14)  = M_G_DQ<14>
  VSS(84)  = GND
  DQ(10)  = M_G_DQ<10>
  VSS(83)  = GND
  DQ(20)  = M_G_DQ<20>
  VSS(82)  = GND
  DQ(16)  = M_G_DQ<16>
  VSS(81)  = GND
  DQS11P  = M_G_DQS_DP<11>
  DQS11N  = M_G_DQS_DN<11>
  VSS(80)  = GND
  DQ(22)  = M_G_DQ<22>
  VSS(79)  = GND
  DQ(18)  = M_G_DQ<18>
  VSS(78)  = GND
  DQ(28)  = M_G_DQ<28>
  VSS(77)  = GND
  DQ(24)  = M_G_DQ<24>
  VSS(76)  = GND
  DQS12P  = M_G_DQS_DP<12>
  DQS12N  = M_G_DQS_DN<12>
  VSS(75)  = GND
  DQ(30)  = M_G_DQ<30>
  VSS(74)  = GND
  DQ(26)  = M_G_DQ<26>
  VSS(73)  = GND
  CB(4)  = M_G_ECC<4>
  VSS(72)  = GND
  CB(0)  = M_G_ECC<0>
  VSS(71)  = GND
  DQS17P  = M_G_DQS_DP<17>
  DQS17N  = M_G_DQS_DN<17>
  VSS(70)  = GND
  CB(6)  = M_G_ECC<6>
  VSS(69)  = GND
  CB(2)  = M_G_ECC<2>
  VSS(68)  = GND
  RESET_N  = M_GHJ_RST_N
  VDD(25)  = PVDDQ_GHJ
  CKE(0)  = M_G_CKE<2>
  VDD(24)  = PVDDQ_GHJ
  ACT_N  = M_G_ACT_N
  BG(0)  = M_G_BG<0>
  VDD(23)  = PVDDQ_GHJ
  A12  = M_G_MA<12>
  A9  = M_G_MA<9>
  VDD(22)  = PVDDQ_GHJ
  A8  = M_G_MA<8>
  A6  = M_G_MA<6>
  VDD(21)  = PVDDQ_GHJ
  A3  = M_G_MA<3>
  A1  = M_G_MA<1>
  VDD(20)  = PVDDQ_GHJ
  CK0P  = M_G_CLK_DP<2>
  CK0N  = M_G_CLK_DN<2>
  VDD(19)  = PVDDQ_GHJ
  VTT(1)  = PVTT_GHJ
  EVENT_N  = FM_DIMM_EVENT_COD_N
  A0  = M_G_MA<0>
  VDD(18)  = PVDDQ_GHJ
  BA(0)  = M_G_BA<0>
  A16_RAS_N  = M_G_MA<16>
  VDD(17)  = PVDDQ_GHJ
  S0_N  = M_G_CS_N<4>
  VDD(16)  = PVDDQ_GHJ
  A15_CAS_N  = M_G_MA<15>
  ODT(0)  = M_G_ODT<2>
  VDD(15)  = PVDDQ_GHJ
  S1_N  = M_G_CS_N<5>
  VDD(14)  = PVDDQ_GHJ
  ODT(1)  = M_G_ODT<3>
  VDD(13)  = PVDDQ_GHJ
  S2_N_C(0)  = M_G_CS_N<6>
  VSS(67)  = GND
  DQ(36)  = M_G_DQ<36>
  VSS(66)  = GND
  DQ(32)  = M_G_DQ<32>
  VSS(65)  = GND
  DQS13P  = M_G_DQS_DP<13>
  DQS13N  = M_G_DQS_DN<13>
  VSS(64)  = GND
  DQ(38)  = M_G_DQ<38>
  VSS(63)  = GND
  DQ(34)  = M_G_DQ<34>
  VSS(62)  = GND
  DQ(44)  = M_G_DQ<44>
  VSS(61)  = GND
  DQ(40)  = M_G_DQ<40>
  VSS(60)  = GND
  DQS14P  = M_G_DQS_DP<14>
  DQS14N  = M_G_DQS_DN<14>
  VSS(59)  = GND
  DQ(46)  = M_G_DQ<46>
  VSS(58)  = GND
  DQ(42)  = M_G_DQ<42>
  VSS(57)  = GND
  DQ(52)  = M_G_DQ<52>
  VSS(56)  = GND
  DQ(48)  = M_G_DQ<48>
  VSS(55)  = GND
  DQS15P  = M_G_DQS_DP<15>
  DQS15N  = M_G_DQS_DN<15>
  VSS(54)  = GND
  DQ(54)  = M_G_DQ<54>
  VSS(53)  = GND
  DQ(50)  = M_G_DQ<50>
  VSS(52)  = GND
  DQ(60)  = M_G_DQ<60>
  VSS(51)  = GND
  DQ(56)  = M_G_DQ<56>
  VSS(50)  = GND
  DQS16P  = M_G_DQS_DP<16>
  DQS16N  = M_G_DQS_DN<16>
  VSS(49)  = GND
  DQ(62)  = M_G_DQ<62>
  VSS(48)  = GND
  DQ(58)  = M_G_DQ<58>
  VSS(47)  = GND
  SA(0)  = PVPP_GHJ
  SA(1)  = GND
  SCL  = SMB_DDR_GHJ_VPP_SCL
  VPP(4)  = PVPP_GHJ
  VPP(3)  = PVPP_GHJ
  RFU(2)  = TP_CH_G_DIMM0_RFU_2
  \12v\(0)  = P12V_NVDIMM_GHJ
  VREFCA  = M_G_VREF
  VSS(46)  = GND
  DQ(5)  = M_G_DQ<5>
  VSS(45)  = GND
  DQ(1)  = M_G_DQ<1>
  VSS(44)  = GND
  DQS0N  = M_G_DQS_DN<0>
  DQS0P  = M_G_DQS_DP<0>
  VSS(43)  = GND
  DQ(7)  = M_G_DQ<7>
  VSS(42)  = GND
  DQ(3)  = M_G_DQ<3>
  VSS(41)  = GND
  DQ(13)  = M_G_DQ<13>
  VSS(40)  = GND
  DQ(9)  = M_G_DQ<9>
  VSS(39)  = GND
  DQS1N  = M_G_DQS_DN<1>
  DQS1P  = M_G_DQS_DP<1>
  VSS(38)  = GND
  DQ(15)  = M_G_DQ<15>
  VSS(37)  = GND
  DQ(11)  = M_G_DQ<11>
  VSS(36)  = GND
  DQ(21)  = M_G_DQ<21>
  VSS(35)  = GND
  DQ(17)  = M_G_DQ<17>
  VSS(34)  = GND
  DQS2N  = M_G_DQS_DN<2>
  DQS2P  = M_G_DQS_DP<2>
  VSS(33)  = GND
  DQ(23)  = M_G_DQ<23>
  VSS(32)  = GND
  DQ(19)  = M_G_DQ<19>
  VSS(31)  = GND
  DQ(29)  = M_G_DQ<29>
  VSS(30)  = GND
  DQ(25)  = M_G_DQ<25>
  VSS(29)  = GND
  DQS3N  = M_G_DQS_DN<3>
  DQS3P  = M_G_DQS_DP<3>
  VSS(28)  = GND
  DQ(31)  = M_G_DQ<31>
  VSS(27)  = GND
  DQ(27)  = M_G_DQ<27>
  VSS(26)  = GND
  CB(5)  = M_G_ECC<5>
  VSS(25)  = GND
  CB(1)  = M_G_ECC<1>
  VSS(24)  = GND
  DQS8N  = M_G_DQS_DN<8>
  DQS8P  = M_G_DQS_DP<8>
  VSS(23)  = GND
  CB(7)  = M_G_ECC<7>
  VSS(22)  = GND
  CB(3)  = M_G_ECC<3>
  VSS(21)  = GND
  CKE(1)  = M_G_CKE<3>
  VDD(12)  = PVDDQ_GHJ
  RFU(0)  = TP_CH_G_DIMM0_RFU_0
  VDD(11)  = PVDDQ_GHJ
  BG(1)  = M_G_BG<1>
  ALERT_N  = M_G_ALERT_N
  VDD(10)  = PVDDQ_GHJ
  A11  = M_G_MA<11>
  A7  = M_G_MA<7>
  VDD(9)  = PVDDQ_GHJ
  A5  = M_G_MA<5>
  A4  = M_G_MA<4>
  VDD(8)  = PVDDQ_GHJ
  A2  = M_G_MA<2>
  VDD(7)  = PVDDQ_GHJ
  CK1P  = M_G_CLK_DP<3>
  CK1N  = M_G_CLK_DN<3>
  VDD(6)  = PVDDQ_GHJ
  VTT(0)  = PVTT_GHJ
  PAR  = M_G_PAR
  VDD(5)  = PVDDQ_GHJ
  BA(1)  = M_G_BA<1>
  A10  = M_G_MA<10>
  VDD(4)  = PVDDQ_GHJ
  RFU(1)  = TP_CH_G_DIMM0_RFU_1
  A14_WE_N  = M_G_MA<14>
  VDD(3)  = PVDDQ_GHJ
  SAVE_N_NC  = FM_ADR_COMPLETE_GHJ_N
  VDD(2)  = PVDDQ_GHJ
  A13  = M_G_MA<13>
  VDD(1)  = PVDDQ_GHJ
  A17  = M_G_MA<17>
  C(2)  = M_G_C<2>
  VDD(0)  = PVDDQ_GHJ
  S3_N_C(1)  = M_G_CS_N<7>
  SA(2)  = GND
  VSS(20)  = GND
  DQ(37)  = M_G_DQ<37>
  VSS(19)  = GND
  DQ(33)  = M_G_DQ<33>
  VSS(18)  = GND
  DQS4N  = M_G_DQS_DN<4>
  DQS4P  = M_G_DQS_DP<4>
  VSS(17)  = GND
  DQ(39)  = M_G_DQ<39>
  VSS(16)  = GND
  DQ(35)  = M_G_DQ<35>
  VSS(15)  = GND
  DQ(45)  = M_G_DQ<45>
  VSS(14)  = GND
  DQ(41)  = M_G_DQ<41>
  VSS(13)  = GND
  DQS5N  = M_G_DQS_DN<5>
  DQS5P  = M_G_DQS_DP<5>
  VSS(12)  = GND
  DQ(47)  = M_G_DQ<47>
  VSS(11)  = GND
  DQ(43)  = M_G_DQ<43>
  VSS(10)  = GND
  DQ(53)  = M_G_DQ<53>
  VSS(9)  = GND
  DQ(49)  = M_G_DQ<49>
  VSS(8)  = GND
  DQS6N  = M_G_DQS_DN<6>
  DQS6P  = M_G_DQS_DP<6>
  VSS(7)  = GND
  DQ(55)  = M_G_DQ<55>
  VSS(6)  = GND
  DQ(51)  = M_G_DQ<51>
  VSS(5)  = GND
  DQ(61)  = M_G_DQ<61>
  VSS(4)  = GND
  DQ(57)  = M_G_DQ<57>
  VSS(3)  = GND
  DQS7N  = M_G_DQS_DN<7>
  DQS7P  = M_G_DQS_DP<7>
  VSS(2)  = GND
  DQ(63)  = M_G_DQ<63>
  VSS(1)  = GND
  DQ(59)  = M_G_DQ<59>
  VSS(0)  = GND
  VDDSPD  = PVPP_GHJ
  SDA  = SMB_DDR_GHJ_VPP_SDA
  VPP(1)  = PVPP_GHJ
  VPP(0)  = PVPP_GHJ
  VPP(2)  = PVPP_GHJ

(kicad_pcb
	(version 20260206)
	(generator "pcbnew")
	(generator_version "10.0")
	(general
		(thickness 1.6)
		(legacy_teardrops no)
	)
	(paper "A4")
	(title_block
		(title "Wiwynn_Tioga_Pass_MB.brd")
		(comment 1 "Tioga Pass / footprint 4084 of 4770 (J9T1), pads 152-201 of 291")
	)
	(layers
		(0 "F.Cu" signal "TOP")
		(4 "In1.Cu" signal "L2GND")
		(6 "In2.Cu" signal "L3")
		(8 "In3.Cu" signal "L4GND")
		(10 "In4.Cu" signal "L5")
		(12 "In5.Cu" signal "L6GND")
		(14 "In6.Cu" signal "L7VCC")
		(16 "In7.Cu" signal "L8VCC")
		(18 "In8.Cu" signal "L9GND")
		(20 "In9.Cu" signal "L10")
		(22 "In10.Cu" signal "L11GND")
		(24 "In11.Cu" signal "L12")
		(26 "In12.Cu" signal "L13GND")
		(2 "B.Cu" signal "BOTTOM")
		(9 "F.Adhes" user "F.Adhesive")
		(11 "B.Adhes" user "B.Adhesive")
		(13 "F.Paste" user "Package Geometry/Pastemask Top")
		(15 "B.Paste" user "Package Geometry/Pastemask Bottom")
		(5 "F.SilkS" user "Ref Des/Silkscreen Top")
		(7 "B.SilkS" user "Ref Des/Silkscreen Bottom")
		(1 "F.Mask" user "Board Geometry/Soldermask Top")
		(3 "B.Mask" user "Board Geometry/Soldermask Bottom")
		(17 "Dwgs.User" user "User.Drawings")
		(19 "Cmts.User" user "User.Comments")
		(21 "Eco1.User" user "User.Eco1")
		(23 "Eco2.User" user "User.Eco2")
		(25 "Edge.Cuts" user "Board Geometry/Outline")
		(27 "Margin" user)
		(31 "F.CrtYd" user "Package Geometry/Place Bound Top")
		(29 "B.CrtYd" user "Package Geometry/Place Bound Bottom")
		(35 "F.Fab" user "Ref Des/Assembly Top")
		(33 "B.Fab" user "Ref Des/Assembly Bottom")
	)
	(footprint ""
		(layer "B.Cu")
		(at 29.699458 -24.824182 90)
		(property "Reference" "J9T1"
			(at 2.200148 39.261542 0)
			(unlocked yes)
			(layer "B.SilkS")
			(effects
				(font
					(size 0.7874 0.5842)
					(thickness 0.1524)
				)
				(justify left mirror)
			)
		)
		(property "Value" ""
			(at 0 0 90)
			(layer "B.Fab")
			(effects
				(font
					(size 1.27 1.27)
				)
				(justify mirror)
			)
		)
		(duplicate_pad_numbers_are_jumpers no)
		(pad "149" smd rect
			(at -4.59994 3.400044 270)
			(size 1.8034 0.508)
			(layers "B.Cu" "B.Mask" "B.Paste")
			(net "GND")
		)
		(pad "150" smd rect
			(at -4.59994 4.249928 270)
			(size 1.8034 0.508)
			(layers "B.Cu" "B.Mask" "B.Paste")
			(net "M_G_DQ<1>")
		)
		(pad "151" smd rect
			(at -4.59994 5.100066 270)
			(size 1.8034 0.508)
			(layers "B.Cu" "B.Mask" "B.Paste")
			(net "GND")
		)
		(pad "152" smd rect
			(at -4.59994 5.94995 270)
			(size 1.8034 0.508)
			(layers "B.Cu" "B.Mask" "B.Paste")
			(net "M_G_DQS_DN<0>")
		)
		(pad "153" smd rect
			(at -4.59994 6.800088 270)
			(size 1.8034 0.508)
			(layers "B.Cu" "B.Mask" "B.Paste")
			(net "M_G_DQS_DP<0>")
		)
		(pad "154" smd rect
			(at -4.59994 7.649972 270)
			(size 1.8034 0.508)
			(layers "B.Cu" "B.Mask" "B.Paste")
			(net "GND")
		)
		(pad "155" smd rect
			(at -4.59994 8.50011 270)
			(size 1.8034 0.508)
			(layers "B.Cu" "B.Mask" "B.Paste")
			(net "M_G_DQ<7>")
		)
		(pad "156" smd rect
			(at -4.59994 9.349994 270)
			(size 1.8034 0.508)
			(layers "B.Cu" "B.Mask" "B.Paste")
			(net "GND")
		)
		(pad "157" smd rect
			(at -4.59994 10.199878 270)
			(size 1.8034 0.508)
			(layers "B.Cu" "B.Mask" "B.Paste")
			(net "M_G_DQ<3>")
		)
		(pad "158" smd rect
			(at -4.59994 11.050016 270)
			(size 1.8034 0.508)
			(layers "B.Cu" "B.Mask" "B.Paste")
			(net "GND")
		)
		(pad "159" smd rect
			(at -4.59994 11.8999 270)
			(size 1.8034 0.508)
			(layers "B.Cu" "B.Mask" "B.Paste")
			(net "M_G_DQ<13>")
		)
		(pad "160" smd rect
			(at -4.59994 12.750038 270)
			(size 1.8034 0.508)
			(layers "B.Cu" "B.Mask" "B.Paste")
			(net "GND")
		)
		(pad "161" smd rect
			(at -4.59994 13.599922 270)
			(size 1.8034 0.508)
			(layers "B.Cu" "B.Mask" "B.Paste")
			(net "M_G_DQ<9>")
		)
		(pad "162" smd rect
			(at -4.59994 14.45006 270)
			(size 1.8034 0.508)
			(layers "B.Cu" "B.Mask" "B.Paste")
			(net "GND")
		)
		(pad "163" smd rect
			(at -4.59994 15.299944 270)
			(size 1.8034 0.508)
			(layers "B.Cu" "B.Mask" "B.Paste")
			(net "M_G_DQS_DN<1>")
		)
		(pad "164" smd rect
			(at -4.59994 16.150082 270)
			(size 1.8034 0.508)
			(layers "B.Cu" "B.Mask" "B.Paste")
			(net "M_G_DQS_DP<1>")
		)
		(pad "165" smd rect
			(at -4.59994 16.999966 270)
			(size 1.8034 0.508)
			(layers "B.Cu" "B.Mask" "B.Paste")
			(net "GND")
		)
		(pad "166" smd rect
			(at -4.59994 17.850104 270)
			(size 1.8034 0.508)
			(layers "B.Cu" "B.Mask" "B.Paste")
			(net "M_G_DQ<15>")
		)
		(pad "167" smd rect
			(at -4.59994 18.699988 270)
			(size 1.8034 0.508)
			(layers "B.Cu" "B.Mask" "B.Paste")
			(net "GND")
		)
		(pad "168" smd rect
			(at -4.59994 19.550126 270)
			(size 1.8034 0.508)
			(layers "B.Cu" "B.Mask" "B.Paste")
			(net "M_G_DQ<11>")
		)
		(pad "169" smd rect
			(at -4.59994 20.40001 270)
			(size 1.8034 0.508)
			(layers "B.Cu" "B.Mask" "B.Paste")
			(net "GND")
		)
		(pad "170" smd rect
			(at -4.59994 21.249894 270)
			(size 1.8034 0.508)
			(layers "B.Cu" "B.Mask" "B.Paste")
			(net "M_G_DQ<21>")
		)
		(pad "171" smd rect
			(at -4.59994 22.100032 270)
			(size 1.8034 0.508)
			(layers "B.Cu" "B.Mask" "B.Paste")
			(net "GND")
		)
		(pad "172" smd rect
			(at -4.59994 22.949916 270)
			(size 1.8034 0.508)
			(layers "B.Cu" "B.Mask" "B.Paste")
			(net "M_G_DQ<17>")
		)
		(pad "173" smd rect
			(at -4.59994 23.800054 270)
			(size 1.8034 0.508)
			(layers "B.Cu" "B.Mask" "B.Paste")
			(net "GND")
		)
		(pad "174" smd rect
			(at -4.59994 24.649938 270)
			(size 1.8034 0.508)
			(layers "B.Cu" "B.Mask" "B.Paste")
			(net "M_G_DQS_DN<2>")
		)
		(pad "175" smd rect
			(at -4.59994 25.500076 270)
			(size 1.8034 0.508)
			(layers "B.Cu" "B.Mask" "B.Paste")
			(net "M_G_DQS_DP<2>")
		)
		(pad "176" smd rect
			(at -4.59994 26.34996 270)
			(size 1.8034 0.508)
			(layers "B.Cu" "B.Mask" "B.Paste")
			(net "GND")
		)
		(pad "177" smd rect
			(at -4.59994 27.200098 270)
			(size 1.8034 0.508)
			(layers "B.Cu" "B.Mask" "B.Paste")
			(net "M_G_DQ<23>")
		)
		(pad "178" smd rect
			(at -4.59994 28.049982 270)
			(size 1.8034 0.508)
			(layers "B.Cu" "B.Mask" "B.Paste")
			(net "GND")
		)
		(pad "179" smd rect
			(at -4.59994 28.90012 270)
			(size 1.8034 0.508)
			(layers "B.Cu" "B.Mask" "B.Paste")
			(net "M_G_DQ<19>")
		)
		(pad "180" smd rect
			(at -4.59994 29.750004 270)
			(size 1.8034 0.508)
			(layers "B.Cu" "B.Mask" "B.Paste")
			(net "GND")
		)
		(pad "181" smd rect
			(at -4.59994 30.599888 270)
			(size 1.8034 0.508)
			(layers "B.Cu" "B.Mask" "B.Paste")
			(net "M_G_DQ<29>")
		)
		(pad "182" smd rect
			(at -4.59994 31.450026 270)
			(size 1.8034 0.508)
			(layers "B.Cu" "B.Mask" "B.Paste")
			(net "GND")
		)
		(pad "183" smd rect
			(at -4.59994 32.29991 270)
			(size 1.8034 0.508)
			(layers "B.Cu" "B.Mask" "B.Paste")
			(net "M_G_DQ<25>")
		)
		(pad "184" smd rect
			(at -4.59994 33.150048 270)
			(size 1.8034 0.508)
			(layers "B.Cu" "B.Mask" "B.Paste")
			(net "GND")
		)
		(pad "185" smd rect
			(at -4.59994 33.999932 270)
			(size 1.8034 0.508)
			(layers "B.Cu" "B.Mask" "B.Paste")
			(net "M_G_DQS_DN<3>")
		)
		(pad "186" smd rect
			(at -4.59994 34.85007 270)
			(size 1.8034 0.508)
			(layers "B.Cu" "B.Mask" "B.Paste")
			(net "M_G_DQS_DP<3>")
		)
		(pad "187" smd rect
			(at -4.59994 35.699954 270)
			(size 1.8034 0.508)
			(layers "B.Cu" "B.Mask" "B.Paste")
			(net "GND")
		)
		(pad "188" smd rect
			(at -4.59994 36.550092 270)
			(size 1.8034 0.508)
			(layers "B.Cu" "B.Mask" "B.Paste")
			(net "M_G_DQ<31>")
		)
		(pad "189" smd rect
			(at -4.59994 37.399976 270)
			(size 1.8034 0.508)
			(layers "B.Cu" "B.Mask" "B.Paste")
			(net "GND")
		)
		(pad "190" smd rect
			(at -4.59994 38.250114 270)
			(size 1.8034 0.508)
			(layers "B.Cu" "B.Mask" "B.Paste")
			(net "M_G_DQ<27>")
		)
		(pad "191" smd rect
			(at -4.59994 39.099998 270)
			(size 1.8034 0.508)
			(layers "B.Cu" "B.Mask" "B.Paste")
			(net "GND")
		)
		(pad "192" smd rect
			(at -4.59994 39.949882 270)
			(size 1.8034 0.508)
			(layers "B.Cu" "B.Mask" "B.Paste")
			(net "M_G_ECC<5>")
		)
		(pad "193" smd rect
			(at -4.59994 40.80002 270)
			(size 1.8034 0.508)
			(layers "B.Cu" "B.Mask" "B.Paste")
			(net "GND")
		)
		(pad "194" smd rect
			(at -4.59994 41.649904 270)
			(size 1.8034 0.508)
			(layers "B.Cu" "B.Mask" "B.Paste")
			(net "M_G_ECC<1>")
		)
		(pad "195" smd rect
			(at -4.59994 42.500042 270)
			(size 1.8034 0.508)
			(layers "B.Cu" "B.Mask" "B.Paste")
			(net "GND")
		)
		(pad "196" smd rect
			(at -4.59994 43.349926 270)
			(size 1.8034 0.508)
			(layers "B.Cu" "B.Mask" "B.Paste")
			(net "M_G_DQS_DN<8>")
		)
		(pad "197" smd rect
			(at -4.59994 44.200064 270)
			(size 1.8034 0.508)
			(layers "B.Cu" "B.Mask" "B.Paste")
			(net "M_G_DQS_DP<8>")
		)
		(pad "198" smd rect
			(at -4.59994 45.049948 270)
			(size 1.8034 0.508)
			(layers "B.Cu" "B.Mask" "B.Paste")
			(net "GND")
		)
	)
)
